# ZAIUS-LV CARD-DVT-X01-BOM-X00_20170420_Final.xls.xlsx — DEPOP_GA (bom)
| FOXCONN TECHNOLOGY GROUP |  |  |  |  |  |  |  |  |  |  |  |  |
| BILL OF MATERIAL |  |  |  |  |  |  |  |  |  |  |  |  |
| REV OF  BOM |  | CUSTOMER | Customer |  | CUSTOMER P/N |  | PRODUCT CODE |  | PWA  REV |  | DATE |  |
| Sourcing (Single/Sole/Multi) | Critical Commodity (Y or N) | Component Class (1, 2, other) | Customer PSL (Y or N) | Item Number | Foxconn P/N | Customer P/N | Part Description | Manufacturer  Full Name | Manufacturer  Part Number | Qty | RoHS Status | Location |
